FILE_TYPE = MACRO_DRAWING;
SET COLOR_WIRE YELLOW;
SET COLOR_PROP MONO;
SET COLOR_DOT WHITE;
SET COLOR_ARC YELLOW;
SET COLOR_BODY GREEN;
SET COLOR_NOTE MONO;
SET PROP_DISPLAY VALUE;
SET PAGE_NUMBER P7;
FORCEADD INTEL_CORP_BPAGE..1
(4400 50);
FORCEPROP 1 LAST CUSTOM_TXT_CDS <CURRENT_DESIGN_SHEET> OF <TOTAL_DESIGN_SHEETS>
J 0
(3900 75);
PAINT GREEN (3900 75);
FORCEPROP 1 LAST CUSTOM_TXT_CDS <CON_LAST_MODIFIED>
J 0
(2475 400);
PAINT GREEN (2475 400);
FORCEPROP 2 LAST CUSTOM_TXT_CDS <XR_PAGE_TITLE>
J 0
(-3490 5300);
DISPLAY 0.638298 (-3490 5300);
PAINT PINK (-3490 5300);
DISPLAY INVISIBLE (-3490 5300);
FORCEPROP 1 LAST SCH_TITLE SMBUS BLOCK DIAGRAM
J 0
(-3550 100);
DISPLAY 1.212766 (-3550 100);
PAINT ORANGE (-3550 100);
FORCEPROP 1 LAST SCH_DEPT BESD
J 1
(-50 150);
DISPLAY 1.212766 (-50 150);
PAINT YELLOW (-50 150);
FORCEPROP 1 LAST SCH_ADDRESS3 Santa Clara, CA 95052-8119
J 0
(425 75);
DISPLAY 0.617021 (425 75);
PAINT GREEN (425 75);
FORCEPROP 1 LAST SCH_ADDRESS2 P.O. BOX 58119
J 0
(425 125);
DISPLAY 0.617021 (425 125);
PAINT GREEN (425 125);
FORCEPROP 1 LAST SCH_ADDRESS1 2200 Mission College Blvd.
J 0
(425 175);
DISPLAY 0.617021 (425 175);
PAINT GREEN (425 175);
FORCEPROP 1 LAST SCH_REV 2.420
J 0
(4150 200);
DISPLAY 0.978723 (4150 200);
PAINT YELLOW (4150 200);
FORCEPROP 1 LAST SCH_NUMBER H4694802
J 0
(3100 200);
DISPLAY 1.212766 (3100 200);
PAINT YELLOW (3100 200);
FORCEPROP 2 LAST CDS_LIB mstr_symbols
J 0
(4400 50);
PAINT MONO (4400 50);
DISPLAY INVISIBLE (4400 50);
FORCEPROP 2 LAST PAGE_BORDER TRUE
J 0
(-3490 5300);
DISPLAY 0.638298 (-3490 5300);
PAINT PINK (-3490 5300);
DISPLAY INVISIBLE (-3490 5300);
FORCEPROP 1 LAST COMMENT_BODY TRUE
J 0
(4412 62);
DISPLAY 0.468085 (4412 62);
PAINT GREEN (4412 62);
DISPLAY INVISIBLE (4412 62);
FORCEPROP 1 LAST CDS_CON_LAST_MODIFIED Tue Dec 01 11:47:56 2015
J 0
(2975 375);
PAINT ORANGE (2975 375);
DISPLAY INVISIBLE (2975 375);
FORCEPROP 2 LAST CDS_XR_PAGE_TITLE CR-7 : @BASEBOARD_FAB2_LIB.BASEBOARD_FAB2(SCH_1):PAGE7
J 0
(-3490 5300);
DISPLAY 0.638298 (-3490 5300);
PAINT PINK (-3490 5300);
DISPLAY INVISIBLE (-3490 5300);
FORCENOTE
$CDS_IMAGE|07_CPU_SMBUS_topology.jpg|5250|4750
(275 2700) 0;
DISPLAY CENTER (275 2700);
PAINT MONO (275 2700);
QUIT
